# T6G (Grand Teton) — schematic netlist excerpt (pin names and nets, part order shuffled) for the footprints in the layout excerpt that follows; sources: Cadence DE-HDL packaged netlist, KiCad conversion of 04192023_DAF0TMB3IC0_F0TG_MB_C_brd_V02_OCP.brd

PC68  Q_CAP  3300PF 50V 10% X7R  pkg 0402  page 200 : A = VSENSE_PVDDCR_CPU1_P0_VSEN0 ; B = VSENSE_VSS_SENSE_C_P0
R3181  Q_RES  27.4 1% CHIP  pkg 0402LF  page 133 : A = CLK_50M_NCSI_OCP_2 ; B = CLK_50M_NCSI_OCP_V3_2

(kicad_pcb
	(version 20260206)
	(generator "pcbnew")
	(generator_version "10.0")
	(general
		(thickness 1.6)
		(legacy_teardrops no)
	)
	(paper "A4")
	(title_block
		(title "04192023_DAF0TMB3IC0_F0TG_MB_C_brd_V02_OCP.brd")
		(comment 1 "Grand Teton / footprints 4476-4477 of 8354")
	)
	(layers
		(0 "F.Cu" signal "TOP")
		(4 "In1.Cu" signal "GND")
		(6 "In2.Cu" signal "IN1")
		(8 "In3.Cu" signal "GND1")
		(10 "In4.Cu" signal "IN2")
		(12 "In5.Cu" signal "GND2")
		(14 "In6.Cu" signal "IN3")
		(16 "In7.Cu" signal "GND3")
		(18 "In8.Cu" signal "VCC")
		(20 "In9.Cu" signal "VCC1")
		(22 "In10.Cu" signal "GND4")
		(24 "In11.Cu" signal "IN4")
		(26 "In12.Cu" signal "GND5")
		(28 "In13.Cu" signal "IN5")
		(30 "In14.Cu" signal "GND6")
		(32 "In15.Cu" signal "IN6")
		(34 "In16.Cu" signal "GND7")
		(2 "B.Cu" signal "BOTTOM")
		(9 "F.Adhes" user "F.Adhesive")
		(11 "B.Adhes" user "B.Adhesive")
		(13 "F.Paste" user "Package Geometry/Pastemask Top")
		(15 "B.Paste" user "Package Geometry/Pastemask Bottom")
		(5 "F.SilkS" user "Ref Des/Silkscreen Top")
		(7 "B.SilkS" user "Ref Des/Silkscreen Bottom")
		(1 "F.Mask" user "Board Geometry/Soldermask Top")
		(3 "B.Mask" user "Board Geometry/Soldermask Bottom")
		(17 "Dwgs.User" user "User.Drawings")
		(19 "Cmts.User" user "User.Comments")
		(21 "Eco1.User" user "User.Eco1")
		(23 "Eco2.User" user "User.Eco2")
		(25 "Edge.Cuts" user "Board Geometry/Outline")
		(27 "Margin" user)
		(31 "F.CrtYd" user "Package Geometry/Place Bound Top")
		(29 "B.CrtYd" user "Package Geometry/Place Bound Bottom")
		(35 "F.Fab" user "Ref Des/Assembly Top")
		(33 "B.Fab" user "Ref Des/Assembly Bottom")
	)
	(footprint ""
		(layer "F.Cu")
		(at 307.213 -355.854)
		(property "Reference" "PC68"
			(at 0 0 0)
			(layer "F.SilkS")
			(hide yes)
			(effects
				(font
					(size 1.27 1.27)
				)
			)
		)
		(property "Value" ""
			(at 0 0 0)
			(layer "F.Fab")
			(effects
				(font
					(size 1.27 1.27)
				)
			)
		)
		(duplicate_pad_numbers_are_jumpers no)
		(fp_line
			(start -0.7874 -0.4064)
			(end 0.7874 -0.4064)
			(stroke
				(width 0.1524)
				(type default)
			)
			(layer "F.SilkS")
		)
		(fp_line
			(start -0.7874 0.4064)
			(end -0.7874 -0.4064)
			(stroke
				(width 0.1524)
				(type default)
			)
			(layer "F.SilkS")
		)
		(fp_line
			(start 0.7874 -0.4064)
			(end 0.7874 0.4064)
			(stroke
				(width 0.1524)
				(type default)
			)
			(layer "F.SilkS")
		)
		(fp_line
			(start 0.7874 0.4064)
			(end -0.7874 0.4064)
			(stroke
				(width 0.1524)
				(type default)
			)
			(layer "F.SilkS")
		)
		(fp_line
			(start -0.67945 -0.305054)
			(end -0.12065 -0.305054)
			(stroke
				(width 0.1)
				(type default)
			)
			(layer "F.Fab")
		)
		(fp_line
			(start -0.67945 0.3048)
			(end -0.67945 -0.305054)
			(stroke
				(width 0.1)
				(type default)
			)
			(layer "F.Fab")
		)
		(fp_line
			(start -0.12065 -0.305054)
			(end -0.12065 -0.2794)
			(stroke
				(width 0.1)
				(type default)
			)
			(layer "F.Fab")
		)
		(fp_line
			(start -0.12065 -0.2794)
			(end 0.12065 -0.2794)
			(stroke
				(width 0.1)
				(type default)
			)
			(layer "F.Fab")
		)
		(fp_line
			(start -0.12065 0.2794)
			(end -0.12065 0.3048)
			(stroke
				(width 0.1)
				(type default)
			)
			(layer "F.Fab")
		)
		(fp_line
			(start -0.12065 0.3048)
			(end -0.67945 0.3048)
			(stroke
				(width 0.1)
				(type default)
			)
			(layer "F.Fab")
		)
		(fp_line
			(start 0.120396 0.2794)
			(end -0.12065 0.2794)
			(stroke
				(width 0.1)
				(type default)
			)
			(layer "F.Fab")
		)
		(fp_line
			(start 0.120396 0.3048)
			(end 0.120396 0.2794)
			(stroke
				(width 0.1)
				(type default)
			)
			(layer "F.Fab")
		)
		(fp_line
			(start 0.12065 -0.3048)
			(end 0.67945 -0.3048)
			(stroke
				(width 0.1)
				(type default)
			)
			(layer "F.Fab")
		)
		(fp_line
			(start 0.12065 -0.2794)
			(end 0.12065 -0.3048)
			(stroke
				(width 0.1)
				(type default)
			)
			(layer "F.Fab")
		)
		(fp_line
			(start 0.67945 -0.3048)
			(end 0.67945 0.3048)
			(stroke
				(width 0.1)
				(type default)
			)
			(layer "F.Fab")
		)
		(fp_line
			(start 0.67945 0.3048)
			(end 0.120396 0.3048)
			(stroke
				(width 0.1)
				(type default)
			)
			(layer "F.Fab")
		)
		(pad "1" smd circle
			(at -0.40005 0)
			(size 0 0)
			(layers "F.Cu" "F.Mask" "F.Paste")
			(net "VSENSE_PVDDCR_CPU1_P0_VSEN0")
		)
		(pad "2" smd circle
			(at 0.40005 0)
			(size 0 0)
			(layers "F.Cu" "F.Mask" "F.Paste")
			(net "VSENSE_VSS_SENSE_C_P0")
		)
	)
	(footprint ""
		(layer "F.Cu")
		(at 217.58402 -16.381222 -90)
		(property "Reference" "R3181"
			(at 0 0 270)
			(layer "F.SilkS")
			(hide yes)
			(effects
				(font
					(size 1.27 1.27)
				)
			)
		)
		(property "Value" ""
			(at 0 0 270)
			(layer "F.Fab")
			(effects
				(font
					(size 1.27 1.27)
				)
			)
		)
		(duplicate_pad_numbers_are_jumpers no)
		(fp_line
			(start -0.7874 0.4064)
			(end -0.7874 -0.4064)
			(stroke
				(width 0.1524)
				(type default)
			)
			(layer "F.SilkS")
		)
		(fp_line
			(start 0.7874 0.4064)
			(end -0.7874 0.4064)
			(stroke
				(width 0.1524)
				(type default)
			)
			(layer "F.SilkS")
		)
		(fp_line
			(start -0.7874 -0.4064)
			(end 0.7874 -0.4064)
			(stroke
				(width 0.1524)
				(type default)
			)
			(layer "F.SilkS")
		)
		(fp_line
			(start 0.7874 -0.4064)
			(end 0.7874 0.4064)
			(stroke
				(width 0.1524)
				(type default)
			)
			(layer "F.SilkS")
		)
		(fp_line
			(start -0.67945 0.3048)
			(end -0.67945 -0.305054)
			(stroke
				(width 0.1)
				(type default)
			)
			(layer "F.Fab")
		)
		(fp_line
			(start -0.12065 0.3048)
			(end -0.67945 0.3048)
			(stroke
				(width 0.1)
				(type default)
			)
			(layer "F.Fab")
		)
		(fp_line
			(start 0.120396 0.3048)
			(end 0.120396 0.2794)
			(stroke
				(width 0.1)
				(type default)
			)
			(layer "F.Fab")
		)
		(fp_line
			(start 0.67945 0.3048)
			(end 0.120396 0.3048)
			(stroke
				(width 0.1)
				(type default)
			)
			(layer "F.Fab")
		)
		(fp_line
			(start -0.12065 0.2794)
			(end -0.12065 0.3048)
			(stroke
				(width 0.1)
				(type default)
			)
			(layer "F.Fab")
		)
		(fp_line
			(start 0.120396 0.2794)
			(end -0.12065 0.2794)
			(stroke
				(width 0.1)
				(type default)
			)
			(layer "F.Fab")
		)
		(fp_line
			(start -0.12065 -0.2794)
			(end 0.12065 -0.2794)
			(stroke
				(width 0.1)
				(type default)
			)
			(layer "F.Fab")
		)
		(fp_line
			(start 0.12065 -0.2794)
			(end 0.12065 -0.3048)
			(stroke
				(width 0.1)
				(type default)
			)
			(layer "F.Fab")
		)
		(fp_line
			(start 0.12065 -0.3048)
			(end 0.67945 -0.3048)
			(stroke
				(width 0.1)
				(type default)
			)
			(layer "F.Fab")
		)
		(fp_line
			(start 0.67945 -0.3048)
			(end 0.67945 0.3048)
			(stroke
				(width 0.1)
				(type default)
			)
			(layer "F.Fab")
		)
		(fp_line
			(start -0.67945 -0.305054)
			(end -0.12065 -0.305054)
			(stroke
				(width 0.1)
				(type default)
			)
			(layer "F.Fab")
		)
		(fp_line
			(start -0.12065 -0.305054)
			(end -0.12065 -0.2794)
			(stroke
				(width 0.1)
				(type default)
			)
			(layer "F.Fab")
		)
		(pad "1" smd circle
			(at -0.40005 0 270)
			(size 0 0)
			(layers "F.Cu" "F.Mask" "F.Paste")
			(net "CLK_50M_NCSI_OCP_2")
		)
		(pad "2" smd circle
			(at 0.40005 0 270)
			(size 0 0)
			(layers "F.Cu" "F.Mask" "F.Paste")
			(net "CLK_50M_NCSI_OCP_V3_2")
		)
	)
)
